(kicad_pcb
	(version 20260206)
	(generator "pcbnew")
	(generator_version "10.0")
	(general
		(thickness 1.21888)
		(legacy_teardrops no)
	)
	(paper "A4")
	(title_block
		(title "timecard-v9 — TimeCard-DC-V9_EXP.PcbDoc")
		(comment 1 "Time Appliance Project (Time Card) / footprints 90-101 of 402")
	)
	(layers
		(0 "F.Cu" signal "TOP")
		(4 "In1.Cu" signal "SGND")
		(6 "In2.Cu" signal "IN1")
		(8 "In3.Cu" signal "IN2")
		(10 "In4.Cu" signal "SGND1")
		(2 "B.Cu" signal "BOTTOM")
		(9 "F.Adhes" user "F.Adhesive")
		(11 "B.Adhes" user "B.Adhesive")
		(13 "F.Paste" user "Top Paste")
		(15 "B.Paste" user "Bottom Paste")
		(5 "F.SilkS" user "Top Overlay")
		(7 "B.SilkS" user "Bottom Overlay")
		(1 "F.Mask" user "Top Solder")
		(3 "B.Mask" user "Bottom Solder")
		(17 "Dwgs.User" user "User.Drawings")
		(19 "Cmts.User" user "User.Comments")
		(21 "Eco1.User" user "User.Eco1")
		(23 "Eco2.User" user "User.Eco2")
		(25 "Edge.Cuts" user)
		(27 "Margin" user)
		(31 "F.CrtYd" user "Top Courtyard")
		(29 "B.CrtYd" user "Bottom Courtyard")
		(35 "F.Fab" user "Top Component Center")
		(33 "B.Fab" user "Bottom Component Center")
	)
	(footprint "Vault:FP-D0008A-MFG"
		(layer "F.Cu")
		(at 86.2116 68.03347)
		(property "Reference" "U17"
			(at -3.2614 -3.290339 0)
			(unlocked yes)
			(layer "F.SilkS")
			(effects
				(font
					(size 0.762 0.762)
					(thickness 0.2286)
				)
			)
		)
		(property "Value" "INA219BIDR"
			(at 3.16004 4.408671 0)
			(unlocked yes)
			(layer "F.SilkS")
			(hide yes)
			(effects
				(font
					(size 0.762 0.762)
					(thickness 0.2286)
				)
			)
		)
		(sheetname "03-POWER")
		(sheetfile "03-POWER.kicad_sch")
		(duplicate_pad_numbers_are_jumpers no)
		(fp_line
			(start -1.5 -2.5)
			(end 1.5 -2.5)
			(stroke
				(width 0.2)
				(type solid)
			)
			(layer "F.SilkS")
		)
		(fp_line
			(start -1.5 2.5)
			(end -1.5 -2.5)
			(stroke
				(width 0.2)
				(type solid)
			)
			(layer "F.SilkS")
		)
		(fp_line
			(start -1.5 2.5)
			(end 1.5 2.5)
			(stroke
				(width 0.2)
				(type solid)
			)
			(layer "F.SilkS")
		)
		(fp_line
			(start 1.5 2.5)
			(end 1.5 -2.5)
			(stroke
				(width 0.2)
				(type solid)
			)
			(layer "F.SilkS")
		)
		(fp_circle
			(center -4.05 -1.905)
			(end -4.05 -2.03)
			(stroke
				(width 0.25)
				(type solid)
			)
			(fill no)
			(layer "F.SilkS")
		)
		(fp_circle
			(center -0.725 -1.725)
			(end -0.725 -1.975)
			(stroke
				(width 0.5)
				(type solid)
			)
			(fill no)
			(layer "F.SilkS")
		)
		(fp_line
			(start -3.575 -2.75)
			(end 3.575 -2.75)
			(stroke
				(width 0.2)
				(type solid)
			)
			(layer "F.CrtYd")
		)
		(fp_line
			(start -3.575 2.75)
			(end -3.575 -2.75)
			(stroke
				(width 0.2)
				(type solid)
			)
			(layer "F.CrtYd")
		)
		(fp_line
			(start -3.575 2.75)
			(end 3.575 2.75)
			(stroke
				(width 0.2)
				(type solid)
			)
			(layer "F.CrtYd")
		)
		(fp_line
			(start 3.575 2.75)
			(end 3.575 -2.75)
			(stroke
				(width 0.2)
				(type solid)
			)
			(layer "F.CrtYd")
		)
		(fp_line
			(start -3.575 -2.75)
			(end 3.575 -2.75)
			(stroke
				(width 0.2)
				(type solid)
			)
			(layer "F.Fab")
		)
		(fp_line
			(start -3.575 2.75)
			(end -3.575 -2.75)
			(stroke
				(width 0.2)
				(type solid)
			)
			(layer "F.Fab")
		)
		(fp_line
			(start -3.575 2.75)
			(end 3.575 2.75)
			(stroke
				(width 0.2)
				(type solid)
			)
			(layer "F.Fab")
		)
		(fp_line
			(start -0.5 0)
			(end 0.5 0)
			(stroke
				(width 0.1)
				(type solid)
			)
			(layer "F.Fab")
		)
		(fp_line
			(start 0 0.5)
			(end 0 -0.5)
			(stroke
				(width 0.1)
				(type solid)
			)
			(layer "F.Fab")
		)
		(fp_line
			(start 3.575 2.75)
			(end 3.575 -2.75)
			(stroke
				(width 0.2)
				(type solid)
			)
			(layer "F.Fab")
		)
		(fp_text user "${REFERENCE}"
			(at -0.00001 0.09601 360)
			(unlocked yes)
			(layer "F.Fab")
			(effects
				(font
					(face "Arial")
					(size 0.63 0.63)
					(thickness 0.1)
				)
				(justify left bottom)
			)
		)
		(pad "1" smd roundrect
			(at -2.7 -1.905)
			(size 1.55 0.6)
			(layers "F.Cu" "F.Mask" "F.Paste")
			(roundrect_rratio 0.085)
			(net "NetR66_1")
			(solder_mask_margin 0)
			(solder_paste_margin 0)
		)
		(pad "2" smd roundrect
			(at -2.7 -0.635)
			(size 1.55 0.6)
			(layers "F.Cu" "F.Mask" "F.Paste")
			(roundrect_rratio 0.085)
			(net "NetR65_1")
			(solder_mask_margin 0)
			(solder_paste_margin 0)
		)
		(pad "3" smd roundrect
			(at -2.7 0.635)
			(size 1.55 0.6)
			(layers "F.Cu" "F.Mask" "F.Paste")
			(roundrect_rratio 0.085)
			(net "SENS_I2C_SDA")
			(solder_mask_margin 0)
			(solder_paste_margin 0)
		)
		(pad "4" smd roundrect
			(at -2.7 1.905)
			(size 1.55 0.6)
			(layers "F.Cu" "F.Mask" "F.Paste")
			(roundrect_rratio 0.085)
			(net "SENS_I2C_SCL")
			(solder_mask_margin 0)
			(solder_paste_margin 0)
		)
		(pad "5" smd roundrect
			(at 2.7 1.905)
			(size 1.55 0.6)
			(layers "F.Cu" "F.Mask" "F.Paste")
			(roundrect_rratio 0.085)
			(net "+3.3V")
			(solder_mask_margin 0)
			(solder_paste_margin 0)
		)
		(pad "6" smd roundrect
			(at 2.7 0.635)
			(size 1.55 0.6)
			(layers "F.Cu" "F.Mask" "F.Paste")
			(roundrect_rratio 0.085)
			(net "GND")
			(solder_mask_margin 0)
			(solder_paste_margin 0)
		)
		(pad "7" smd roundrect
			(at 2.7 -0.635)
			(size 1.55 0.6)
			(layers "F.Cu" "F.Mask" "F.Paste")
			(roundrect_rratio 0.085)
			(net "+5.0V")
			(solder_mask_margin 0)
			(solder_paste_margin 0)
		)
		(pad "8" smd roundrect
			(at 2.7 -1.905)
			(size 1.55 0.6)
			(layers "F.Cu" "F.Mask" "F.Paste")
			(roundrect_rratio 0.085)
			(net "P5V_SENSE")
			(solder_mask_margin 0)
			(solder_paste_margin 0)
		)
	)
	(footprint "Vault:RESC1005X40X25LL05T05"
		(layer "F.Cu")
		(at 84.65686 83.46371)
		(property "Reference" "R108"
			(at -2.87139 0.226921 0)
			(unlocked yes)
			(layer "F.SilkS")
			(effects
				(font
					(size 0.762 0.762)
					(thickness 0.2286)
				)
			)
		)
		(property "Value" "4.7K_0402"
			(at -2.389351 6.513005 270)
			(unlocked yes)
			(layer "F.SilkS")
			(hide yes)
			(effects
				(font
					(size 0.762 0.762)
					(thickness 0.2032)
				)
			)
		)
		(sheetname "02-USER_IO_STATUS")
		(sheetfile "02-USER_IO_STATUS.kicad_sch")
		(duplicate_pad_numbers_are_jumpers no)
		(pad "1" smd rect
			(at -0.39999 0 90)
			(size 0.45 0.45)
			(layers "F.Cu" "F.Mask" "F.Paste")
			(net "+3.3V")
		)
		(pad "2" smd rect
			(at 0.40001 0 90)
			(size 0.45 0.45)
			(layers "F.Cu" "F.Mask" "F.Paste")
			(net "NetR108_2")
		)
	)
	(footprint "Vault:RESC1005X40X25NL10T10"
		(layer "F.Cu")
		(at 174.1216 118.8162 -90)
		(property "Reference" "R118"
			(at 2.7032 -0.208719 270)
			(unlocked yes)
			(layer "F.SilkS")
			(effects
				(font
					(size 0.762 0.762)
					(thickness 0.2032)
				)
			)
		)
		(property "Value" "4.7K_1%_0402"
			(at -2.732271 8.747475 180)
			(unlocked yes)
			(layer "F.SilkS")
			(hide yes)
			(effects
				(font
					(size 0.762 0.762)
					(thickness 0.2032)
				)
			)
		)
		(sheetname "08-DIPSwitches_I2C")
		(sheetfile "08-DIPSwitches_I2C.kicad_sch")
		(duplicate_pad_numbers_are_jumpers no)
		(pad "1" smd rect
			(at -0.425 0)
			(size 0.6 0.65)
			(layers "F.Cu" "F.Mask" "F.Paste")
			(net "SENS_I2C_SCL")
		)
		(pad "2" smd rect
			(at 0.425 0)
			(size 0.6 0.65)
			(layers "F.Cu" "F.Mask" "F.Paste")
			(net "+3.3V")
		)
	)
	(footprint "GNSS:GNSS"
		(locked yes)
		(layer "F.Cu")
		(at 211.5592 136.4387 90)
		(property "Reference" "U15"
			(at 61.895579 -6.509 0)
			(unlocked yes)
			(layer "F.SilkS")
			(effects
				(font
					(size 0.762 0.762)
					(thickness 0.2286)
				)
			)
		)
		(property "Value" "RCB-F9T-1"
			(at -7.786871 -13.756155 0)
			(unlocked yes)
			(layer "F.SilkS")
			(hide yes)
			(effects
				(font
					(size 0.762 0.762)
					(thickness 0.2286)
				)
			)
		)
		(sheetname "05-GPS_IMU_SENSORS")
		(sheetfile "05-GPS_IMU_SENSORS.kicad_sch")
		(duplicate_pad_numbers_are_jumpers no)
		(fp_line
			(start 61.07 -20.47)
			(end 61.07 11.28)
			(stroke
				(width 0.254)
				(type solid)
			)
			(layer "F.SilkS")
		)
		(fp_line
			(start -6.11 -20.47)
			(end 61.07 -20.47)
			(stroke
				(width 0.254)
				(type solid)
			)
			(layer "F.SilkS")
		)
		(fp_line
			(start -6.11 -20.47)
			(end -6.11 11.28)
			(stroke
				(width 0.254)
				(type solid)
			)
			(layer "F.SilkS")
		)
		(fp_line
			(start -6.11 11.28)
			(end 61.07 11.28)
			(stroke
				(width 0.254)
				(type solid)
			)
			(layer "F.SilkS")
		)
		(pad "0" thru_hole circle
			(at 0 -2)
			(size 0 0)
			(drill 0.76)
			(layers "*.Cu" "*.Mask")
			(remove_unused_layers no)
			(thermal_bridge_angle 90)
		)
		(pad "0" thru_hole circle
			(at 0 2)
			(size 0 0)
			(drill 0.76)
			(layers "*.Cu" "*.Mask")
			(remove_unused_layers no)
			(thermal_bridge_angle 90)
		)
		(pad "1" smd rect
			(at -2.2225 3)
			(size 1.12 2.105)
			(layers "F.Cu" "F.Mask" "F.Paste")
			(net "GNSS2_P5V0")
		)
		(pad "2" smd rect
			(at 2.2225 3)
			(size 1.12 2.105)
			(layers "F.Cu" "F.Mask" "F.Paste")
			(net "GNSS2_P3V3")
		)
		(pad "3" smd rect
			(at -2.2225 1)
			(size 1.12 2.105)
			(layers "F.Cu" "F.Mask" "F.Paste")
			(net "RCB_GPS2_TX")
		)
		(pad "4" smd rect
			(at 2.2225 1)
			(size 1.12 2.105)
			(layers "F.Cu" "F.Mask" "F.Paste")
			(net "GPS2_RST")
		)
		(pad "5" smd rect
			(at -2.2225 -1)
			(size 1.12 2.105)
			(layers "F.Cu" "F.Mask" "F.Paste")
			(net "RCB_GPS2_RX")
		)
		(pad "6" smd rect
			(at 2.2225 -1)
			(size 1.12 2.105)
			(layers "F.Cu" "F.Mask" "F.Paste")
			(net "RCB_GPS2_TP1")
		)
		(pad "7" smd rect
			(at -2.2225 -3)
			(size 1.12 2.105)
			(layers "F.Cu" "F.Mask" "F.Paste")
			(net "RCB_GPS2_TP2")
		)
		(pad "8" smd rect
			(at 2.2225 -3)
			(size 1.12 2.105)
			(layers "F.Cu" "F.Mask" "F.Paste")
			(net "GND")
		)
	)
	(footprint "Vault:SOT143-4L"
		(layer "F.Cu")
		(at 71.8716 101.5662 90)
		(property "Reference" "D1"
			(at -0.572805 2.464089 270)
			(unlocked yes)
			(layer "F.SilkS")
			(effects
				(font
					(size 0.762 0.762)
					(thickness 0.2286)
				)
			)
		)
		(property "Value" "8240136"
			(at 2.6781 3.341871 90)
			(unlocked yes)
			(layer "F.SilkS")
			(hide yes)
			(effects
				(font
					(size 0.762 0.762)
					(thickness 0.2286)
				)
			)
		)
		(sheetname "01-USER_IO")
		(sheetfile "01-USER_IO.kicad_sch")
		(duplicate_pad_numbers_are_jumpers no)
		(fp_line
			(start 2.05 -1.7)
			(end 2.05 1.7)
			(stroke
				(width 0.2)
				(type solid)
			)
			(layer "F.SilkS")
		)
		(fp_line
			(start -2.05 -1.7)
			(end 2.05 -1.7)
			(stroke
				(width 0.2)
				(type solid)
			)
			(layer "F.SilkS")
		)
		(fp_line
			(start -2.05 -1.7)
			(end -2.05 1.675)
			(stroke
				(width 0.2)
				(type solid)
			)
			(layer "F.SilkS")
		)
		(fp_line
			(start -2.05 1.7)
			(end 2.05 1.7)
			(stroke
				(width 0.2)
				(type solid)
			)
			(layer "F.SilkS")
		)
		(fp_circle
			(center -2.404 -1.075)
			(end -2.15 -1.075)
			(stroke
				(width 0.2)
				(type solid)
			)
			(fill no)
			(layer "F.SilkS")
		)
		(pad "1" smd rect
			(at -1.1 -0.75 180)
			(size 1.4 1.4)
			(layers "F.Cu" "F.Mask" "F.Paste")
			(net "GND")
		)
		(pad "2" smd rect
			(at -1.1 0.95 180)
			(size 1 1.4)
			(layers "F.Cu" "F.Mask" "F.Paste")
			(net "NetAN2_1")
		)
		(pad "3" smd rect
			(at 1.1 0.95 180)
			(size 1 1.4)
			(layers "F.Cu" "F.Mask" "F.Paste")
			(net "NetAN1_1")
		)
		(pad "4" smd rect
			(at 1.1 -0.95 180)
			(size 1 1.4)
			(layers "F.Cu" "F.Mask" "F.Paste")
			(net "+3.3V")
		)
	)
	(footprint "Vault:FP-LTST-C191KGKT-MFG"
		(layer "F.Cu")
		(at 79.4216 53.8662)
		(property "Reference" "D10"
			(at -2.5714 0.389861 0)
			(unlocked yes)
			(layer "F.SilkS")
			(effects
				(font
					(size 0.762 0.762)
					(thickness 0.2286)
				)
			)
		)
		(property "Value" "LTST-C191KGKT"
			(at 1.2818 2.452871 0)
			(unlocked yes)
			(layer "F.SilkS")
			(hide yes)
			(effects
				(font
					(size 0.762 0.762)
					(thickness 0.2286)
				)
			)
		)
		(sheetname "02-USER_IO_STATUS")
		(sheetfile "02-USER_IO_STATUS.kicad_sch")
		(duplicate_pad_numbers_are_jumpers no)
		(fp_line
			(start -0.85 -0.775)
			(end 0.85 -0.775)
			(stroke
				(width 0.2)
				(type solid)
			)
			(layer "F.SilkS")
		)
		(fp_line
			(start -0.85 0.775)
			(end 0.85 0.775)
			(stroke
				(width 0.2)
				(type solid)
			)
			(layer "F.SilkS")
		)
		(fp_circle
			(center -1.7 0)
			(end -1.7 -0.125)
			(stroke
				(width 0.25)
				(type solid)
			)
			(fill no)
			(layer "F.SilkS")
		)
		(fp_line
			(start -1.25 -0.55)
			(end 1.25 -0.55)
			(stroke
				(width 0.2)
				(type solid)
			)
			(layer "F.CrtYd")
		)
		(fp_line
			(start -1.25 0.55)
			(end -1.25 -0.55)
			(stroke
				(width 0.2)
				(type solid)
			)
			(layer "F.CrtYd")
		)
		(fp_line
			(start -1.25 0.55)
			(end 1.25 0.55)
			(stroke
				(width 0.2)
				(type solid)
			)
			(layer "F.CrtYd")
		)
		(fp_line
			(start 1.25 0.55)
			(end 1.25 -0.55)
			(stroke
				(width 0.2)
				(type solid)
			)
			(layer "F.CrtYd")
		)
		(fp_line
			(start -1.25 -0.55)
			(end 1.25 -0.55)
			(stroke
				(width 0.2)
				(type solid)
			)
			(layer "F.Fab")
		)
		(fp_line
			(start -1.25 0.55)
			(end -1.25 -0.55)
			(stroke
				(width 0.2)
				(type solid)
			)
			(layer "F.Fab")
		)
		(fp_line
			(start -1.25 0.55)
			(end 1.25 0.55)
			(stroke
				(width 0.2)
				(type solid)
			)
			(layer "F.Fab")
		)
		(fp_line
			(start -0.5 0)
			(end 0.5 0)
			(stroke
				(width 0.1)
				(type solid)
			)
			(layer "F.Fab")
		)
		(fp_line
			(start 0 0.5)
			(end 0 -0.5)
			(stroke
				(width 0.1)
				(type solid)
			)
			(layer "F.Fab")
		)
		(fp_line
			(start 1.25 0.55)
			(end 1.25 -0.55)
			(stroke
				(width 0.2)
				(type solid)
			)
			(layer "F.Fab")
		)
		(fp_text user "${REFERENCE}"
			(at 0 0.28425 360)
			(unlocked yes)
			(layer "F.Fab")
			(effects
				(font
					(face "Arial")
					(size 0.63 0.63)
					(thickness 0.1)
				)
				(justify left bottom)
			)
		)
		(pad "1" smd rect
			(at -0.75 0)
			(size 0.8 0.8)
			(layers "F.Cu" "F.Mask" "F.Paste")
			(net "NetD10_1")
			(solder_mask_margin 0)
			(solder_paste_margin 0)
		)
		(pad "2" smd rect
			(at 0.75 0)
			(size 0.8 0.8)
			(layers "F.Cu" "F.Mask" "F.Paste")
			(net "+3.3V")
			(solder_mask_margin 0)
			(solder_paste_margin 0)
		)
	)
	(footprint "Vault:RESC1005X40X25NL10T10"
		(layer "F.Cu")
		(at 175.6216 114.3162)
		(property "Reference" "R116"
			(at 2.8032 0.026931 0)
			(unlocked yes)
			(layer "F.SilkS")
			(effects
				(font
					(size 0.762 0.762)
					(thickness 0.2032)
				)
			)
		)
		(property "Value" "4.7K_1%_0402"
			(at -2.732271 8.747465 270)
			(unlocked yes)
			(layer "F.SilkS")
			(hide yes)
			(effects
				(font
					(size 0.762 0.762)
					(thickness 0.2032)
				)
			)
		)
		(sheetname "08-DIPSwitches_I2C")
		(sheetfile "08-DIPSwitches_I2C.kicad_sch")
		(duplicate_pad_numbers_are_jumpers no)
		(pad "1" smd rect
			(at -0.425 0 90)
			(size 0.6 0.65)
			(layers "F.Cu" "F.Mask" "F.Paste")
			(net "ANADC_I2C_SCL")
		)
		(pad "2" smd rect
			(at 0.425 0 90)
			(size 0.6 0.65)
			(layers "F.Cu" "F.Mask" "F.Paste")
			(net "+3.3V")
		)
	)
	(footprint "Vault:RESC1005X40X25NL10T10"
		(layer "F.Cu")
		(at 166.9216 110.4162 180)
		(property "Reference" "R123"
			(at 2.2968 0.073079 0)
			(unlocked yes)
			(layer "F.SilkS")
			(effects
				(font
					(size 0.762 0.762)
					(thickness 0.2032)
				)
			)
		)
		(property "Value" "4.7K_1%_0402"
			(at -2.732271 8.747465 90)
			(unlocked yes)
			(layer "F.SilkS")
			(hide yes)
			(effects
				(font
					(size 0.762 0.762)
					(thickness 0.2032)
				)
			)
		)
		(sheetname "08-DIPSwitches_I2C")
		(sheetfile "08-DIPSwitches_I2C.kicad_sch")
		(duplicate_pad_numbers_are_jumpers no)
		(pad "1" smd rect
			(at -0.425 0 270)
			(size 0.6 0.65)
			(layers "F.Cu" "F.Mask" "F.Paste")
			(net "SDA")
		)
		(pad "2" smd rect
			(at 0.425 0 270)
			(size 0.6 0.65)
			(layers "F.Cu" "F.Mask" "F.Paste")
			(net "+3.3V")
		)
	)
	(footprint "Vault:RESC1005X40X25NL05T05"
		(layer "F.Cu")
		(at 111.1216 58.2162 -90)
		(property "Reference" "R164"
			(at 2.7032 -0.373069 270)
			(unlocked yes)
			(layer "F.SilkS")
			(effects
				(font
					(size 0.762 0.762)
					(thickness 0.2032)
				)
			)
		)
		(property "Value" "DNI_27_1%_0402"
			(at -2.732271 10.270975 180)
			(unlocked yes)
			(layer "F.SilkS")
			(hide yes)
			(effects
				(font
					(size 0.762 0.762)
					(thickness 0.2032)
				)
			)
		)
		(sheetname "11-M2_RCB_MUX")
		(sheetfile "11-M2_RCB_MUX.kicad_sch")
		(duplicate_pad_numbers_are_jumpers no)
		(pad "1" smd rect
			(at -0.45 0)
			(size 0.55 0.55)
			(layers "F.Cu" "F.Mask" "F.Paste")
			(net "M2_GPS1_TP1")
		)
		(pad "2" smd rect
			(at 0.45 0)
			(size 0.55 0.55)
			(layers "F.Cu" "F.Mask" "F.Paste")
			(net "GPS1_TP1")
		)
	)
	(footprint "Vault:RESC1005X40X25NL10T10"
		(layer "F.Cu")
		(at 71.8216 143.4162 90)
		(property "Reference" "R32"
			(at -0.1714 -1.173069 90)
			(unlocked yes)
			(layer "F.SilkS")
			(effects
				(font
					(size 0.762 0.762)
					(thickness 0.2286)
				)
			)
		)
		(property "Value" "4.7K_1%_0402"
			(at -3.087871 2.374035 0)
			(unlocked yes)
			(layer "F.SilkS")
			(hide yes)
			(effects
				(font
					(size 0.762 0.762)
					(thickness 0.2286)
				)
			)
		)
		(sheetname "01-USER_IO")
		(sheetfile "01-USER_IO.kicad_sch")
		(duplicate_pad_numbers_are_jumpers no)
		(pad "1" smd rect
			(at -0.425 0 180)
			(size 0.6 0.65)
			(layers "F.Cu" "F.Mask" "F.Paste")
			(net "+3.3V")
		)
		(pad "2" smd rect
			(at 0.425 0 180)
			(size 0.6 0.65)
			(layers "F.Cu" "F.Mask" "F.Paste")
			(net "ANT4_IO_IN")
		)
	)
	(footprint "Vault:CAPC1608X87X45ML20T05"
		(layer "F.Cu")
		(at 136.40433 85.04267 -90)
		(property "Reference" "C63"
			(at 0.17353 0.789385 90)
			(unlocked yes)
			(layer "F.SilkS")
			(effects
				(font
					(size 0.762 0.762)
					(thickness 0.2286)
				)
				(justify left bottom)
			)
		)
		(property "Value" "0.1uF"
			(at 1.829705 -4.27005 0)
			(unlocked yes)
			(layer "F.SilkS")
			(hide yes)
			(effects
				(font
					(size 0.762 0.762)
					(thickness 0.2286)
				)
				(justify left bottom)
			)
		)
		(sheetname "06-MAC")
		(sheetfile "06-MAC.kicad_sch")
		(duplicate_pad_numbers_are_jumpers no)
		(pad "1" smd rect
			(at -0.7 0)
			(size 1.1 1.05)
			(layers "F.Cu" "F.Mask" "F.Paste")
			(net "GND")
		)
		(pad "2" smd rect
			(at 0.7 0)
			(size 1.1 1.05)
			(layers "F.Cu" "F.Mask" "F.Paste")
			(net "MAC_VCC")
		)
	)
	(footprint "Vault:RESC1005X40X25LL05T05"
		(layer "F.Cu")
		(at 113.2216 70.1162 180)
		(property "Reference" "R138"
			(at -0.373069 -2.21891 270)
			(unlocked yes)
			(layer "F.SilkS")
			(effects
				(font
					(size 0.762 0.762)
					(thickness 0.2032)
				)
			)
		)
		(property "Value" "0_1%_0402"
			(at -2.579871 6.63996 90)
			(unlocked yes)
			(layer "F.SilkS")
			(hide yes)
			(effects
				(font
					(size 0.762 0.762)
					(thickness 0.2032)
				)
			)
		)
		(sheetname "10-M2_GPS")
		(sheetfile "10-M2_GPS.kicad_sch")
		(duplicate_pad_numbers_are_jumpers no)
		(pad "1" smd rect
			(at -0.4 0 270)
			(size 0.45 0.45)
			(layers "F.Cu" "F.Mask" "F.Paste")
			(net "NetJ44_46")
		)
		(pad "2" smd rect
			(at 0.4 0 270)
			(size 0.45 0.45)
			(layers "F.Cu" "F.Mask" "F.Paste")
			(net "M2_GPS1_TP1")
		)
	)
)
